(kicad_pcb
	(version 20241229)
	(generator "pcbnew")
	(generator_version "9.0")
	(general
		(thickness 1.294)
		(legacy_teardrops no)
	)
	(paper "A3")
	(title_block
		(title "Kintex 410T devboard")
		(date "2024-04-03")
		(rev "1.1.2")
		(comment 9 "footprints 263-267 of 975")
	)
	(layers
		(0 "F.Cu" mixed)
		(4 "In1.Cu" power)
		(6 "In2.Cu" power)
		(8 "In3.Cu" mixed)
		(10 "In4.Cu" power)
		(12 "In5.Cu" mixed)
		(14 "In6.Cu" power)
		(16 "In7.Cu" mixed)
		(18 "In8.Cu" power)
		(2 "B.Cu" mixed)
		(9 "F.Adhes" user "F.Adhesive")
		(11 "B.Adhes" user "B.Adhesive")
		(13 "F.Paste" user)
		(15 "B.Paste" user)
		(5 "F.SilkS" user "F.Silkscreen")
		(7 "B.SilkS" user "B.Silkscreen")
		(1 "F.Mask" user)
		(3 "B.Mask" user)
		(17 "Dwgs.User" user "User.Drawings")
		(19 "Cmts.User" user "User.Comments")
		(21 "Eco1.User" user "User.Eco1")
		(23 "Eco2.User" user "User.Eco2")
		(25 "Edge.Cuts" user)
		(27 "Margin" user)
		(31 "F.CrtYd" user "F.Courtyard")
		(29 "B.CrtYd" user "B.Courtyard")
		(35 "F.Fab" user)
		(33 "B.Fab" user)
	)
	(footprint "antmicro-footprints:C_0402_1005Metric"
		(layer "F.Cu")
		(at 173.570001 122.382501 180)
		(descr "Capacitor SMD 0402")
		(tags "capacitor SMD 0402")
		(property "Reference" "C313"
			(at -3.729999 -0.369999 0)
			(layer "F.SilkS")
			(effects
				(font
					(size 0.7 0.7)
					(thickness 0.15)
				)
				(justify right bottom)
			)
		)
		(property "Value" "C_100n_0402"
			(at 0 1.4 0)
			(layer "F.Fab")
			(effects
				(font
					(size 0.7 0.7)
					(thickness 0.15)
				)
				(justify right bottom)
			)
		)
		(property "Description" "SMD Multilayer Ceramic Capacitor, 0.1 µF, 50 V, 0402 [1005 Metric], ± 10%, X5R, GRM Series"
			(at 0 0 180)
			(layer "F.Fab")
			(hide yes)
			(effects
				(font
					(size 1.27 1.27)
					(thickness 0.15)
				)
			)
		)
		(property "Author" "Antmicro"
			(at 347.140002 244.765002 0)
			(layer "F.Fab")
			(hide yes)
			(effects
				(font
					(size 1 1)
					(thickness 0.15)
				)
			)
		)
		(property "Dielectric" "X5R"
			(at 347.140002 244.765002 0)
			(layer "F.Fab")
			(hide yes)
			(effects
				(font
					(size 1 1)
					(thickness 0.15)
				)
			)
		)
		(property "License" "Apache-2.0"
			(at 347.140002 244.765002 0)
			(layer "F.Fab")
			(hide yes)
			(effects
				(font
					(size 1 1)
					(thickness 0.15)
				)
			)
		)
		(property "MPN" "GRM155R61H104KE14D"
			(at 347.140002 244.765002 0)
			(layer "F.Fab")
			(hide yes)
			(effects
				(font
					(size 1 1)
					(thickness 0.15)
				)
			)
		)
		(property "Manufacturer" "Murata"
			(at 347.140002 244.765002 0)
			(layer "F.Fab")
			(hide yes)
			(effects
				(font
					(size 1 1)
					(thickness 0.15)
				)
			)
		)
		(property "Val" "100n"
			(at 347.140002 244.765002 0)
			(layer "F.Fab")
			(hide yes)
			(effects
				(font
					(size 1 1)
					(thickness 0.15)
				)
			)
		)
		(property "Voltage" "50V"
			(at 347.140002 244.765002 0)
			(layer "F.Fab")
			(hide yes)
			(effects
				(font
					(size 1 1)
					(thickness 0.15)
				)
			)
		)
		(sheetname "FMC+ HSPC")
		(sheetfile "fmc-hspc.kicad_sch")
		(attr smd)
		(fp_rect
			(start -0.925 -0.47)
			(end 0.925 0.47)
			(stroke
				(width 0.05)
				(type default)
			)
			(fill no)
			(layer "F.CrtYd")
		)
		(fp_line
			(start 0.504 0.248)
			(end -0.494 0.248)
			(stroke
				(width 0.15)
				(type solid)
			)
			(layer "F.Fab")
		)
		(fp_line
			(start 0.504 -0.25)
			(end 0.504 0.248)
			(stroke
				(width 0.15)
				(type solid)
			)
			(layer "F.Fab")
		)
		(fp_line
			(start -0.494 0.248)
			(end -0.494 -0.25)
			(stroke
				(width 0.15)
				(type solid)
			)
			(layer "F.Fab")
		)
		(fp_line
			(start -0.494 -0.25)
			(end 0.504 -0.25)
			(stroke
				(width 0.15)
				(type solid)
			)
			(layer "F.Fab")
		)
		(pad "1" smd roundrect
			(at -0.48 0 180)
			(size 0.59 0.64)
			(layers "F.Cu" "F.Mask" "F.Paste")
			(roundrect_rratio 0.25)
			(net 124 "/FMC+ HSPC/GTX115.TX0_N")
			(pintype "passive")
		)
		(pad "2" smd roundrect
			(at 0.48 0 180)
			(size 0.59 0.64)
			(layers "F.Cu" "F.Mask" "F.Paste")
			(roundrect_rratio 0.25)
			(net 123 "/FMC+ HSPC/GTX_TX7_C_N")
			(pintype "passive")
		)
	)
	(footprint "antmicro-footprints:C_0402_1005Metric"
		(layer "F.Cu")
		(at 196.1 166.249 180)
		(descr "Capacitor SMD 0402")
		(tags "capacitor SMD 0402")
		(property "Reference" "C354"
			(at -3.7 -0.151 0)
			(layer "F.SilkS")
			(effects
				(font
					(size 0.7 0.7)
					(thickness 0.15)
				)
				(justify right bottom)
			)
		)
		(property "Value" "C_22n_0402"
			(at 0 1.4 0)
			(layer "F.Fab")
			(effects
				(font
					(size 0.7 0.7)
					(thickness 0.15)
				)
				(justify right bottom)
			)
		)
		(property "Description" "SMD Multilayer Ceramic Capacitors, 0.022 µF, 50 V, 20%, 0402 [1005 Metric], X7R"
			(at 0 0 180)
			(layer "F.Fab")
			(hide yes)
			(effects
				(font
					(size 1.27 1.27)
					(thickness 0.15)
				)
			)
		)
		(property "Author" "Antmicro"
			(at 392.2 332.498 0)
			(layer "F.Fab")
			(hide yes)
			(effects
				(font
					(size 1 1)
					(thickness 0.15)
				)
			)
		)
		(property "Dielectric" ""
			(at 392.2 332.498 0)
			(layer "F.Fab")
			(hide yes)
			(effects
				(font
					(size 1 1)
					(thickness 0.15)
				)
			)
		)
		(property "License" "Apache-2.0"
			(at 392.2 332.498 0)
			(layer "F.Fab")
			(hide yes)
			(effects
				(font
					(size 1 1)
					(thickness 0.15)
				)
			)
		)
		(property "MPN" "GCM155R71H223MA55D"
			(at 392.2 332.498 0)
			(layer "F.Fab")
			(hide yes)
			(effects
				(font
					(size 1 1)
					(thickness 0.15)
				)
			)
		)
		(property "Manufacturer" "Murata"
			(at 392.2 332.498 0)
			(layer "F.Fab")
			(hide yes)
			(effects
				(font
					(size 1 1)
					(thickness 0.15)
				)
			)
		)
		(property "Val" "22n"
			(at 392.2 332.498 0)
			(layer "F.Fab")
			(hide yes)
			(effects
				(font
					(size 1 1)
					(thickness 0.15)
				)
			)
		)
		(property "Voltage" ""
			(at 392.2 332.498 0)
			(layer "F.Fab")
			(hide yes)
			(effects
				(font
					(size 1 1)
					(thickness 0.15)
				)
			)
		)
		(sheetname "DC-DC Converters")
		(sheetfile "dc-dc.kicad_sch")
		(attr smd)
		(fp_rect
			(start -0.925 -0.47)
			(end 0.925 0.47)
			(stroke
				(width 0.05)
				(type default)
			)
			(fill no)
			(layer "F.CrtYd")
		)
		(fp_line
			(start 0.504 0.248)
			(end -0.494 0.248)
			(stroke
				(width 0.15)
				(type solid)
			)
			(layer "F.Fab")
		)
		(fp_line
			(start 0.504 -0.25)
			(end 0.504 0.248)
			(stroke
				(width 0.15)
				(type solid)
			)
			(layer "F.Fab")
		)
		(fp_line
			(start -0.494 0.248)
			(end -0.494 -0.25)
			(stroke
				(width 0.15)
				(type solid)
			)
			(layer "F.Fab")
		)
		(fp_line
			(start -0.494 -0.25)
			(end 0.504 -0.25)
			(stroke
				(width 0.15)
				(type solid)
			)
			(layer "F.Fab")
		)
		(pad "1" smd roundrect
			(at -0.48 0 180)
			(size 0.59 0.64)
			(layers "F.Cu" "F.Mask" "F.Paste")
			(roundrect_rratio 0.25)
			(net 1 "GND")
			(pintype "passive")
		)
		(pad "2" smd roundrect
			(at 0.48 0 180)
			(size 0.59 0.64)
			(layers "F.Cu" "F.Mask" "F.Paste")
			(roundrect_rratio 0.25)
			(net 749 "/DC-DC Converters/1V0_SS")
			(pintype "passive")
		)
	)
	(footprint "antmicro-footprints:R_0402_1005Metric"
		(layer "F.Cu")
		(at 210.91 154.68 -90)
		(descr "Resistor SMD 0402")
		(tags "resistor SMD 0402")
		(property "Reference" "R65"
			(at -0.96 0.35 270)
			(layer "F.SilkS")
			(effects
				(font
					(size 0.7 0.7)
					(thickness 0.15)
				)
				(justify left bottom)
			)
		)
		(property "Value" "R_10k_0402"
			(at 0 1.4 270)
			(layer "F.Fab")
			(effects
				(font
					(size 0.7 0.7)
					(thickness 0.15)
				)
				(justify left bottom)
			)
		)
		(property "Description" "SMD Chip Resistor, 10 kohm, ± 1%, 62.5 mW, 0402 [1005 Metric], Thick Film, General Purpose"
			(at 0 0 270)
			(layer "F.Fab")
			(hide yes)
			(effects
				(font
					(size 1.27 1.27)
					(thickness 0.15)
				)
			)
		)
		(property "Author" "Antmicro"
			(at 56.23 365.59 0)
			(layer "F.Fab")
			(hide yes)
			(effects
				(font
					(size 1 1)
					(thickness 0.15)
				)
			)
		)
		(property "License" "Apache-2.0"
			(at 56.23 365.59 0)
			(layer "F.Fab")
			(hide yes)
			(effects
				(font
					(size 1 1)
					(thickness 0.15)
				)
			)
		)
		(property "MPN" "CR0402-FX-1002GLF"
			(at 56.23 365.59 0)
			(layer "F.Fab")
			(hide yes)
			(effects
				(font
					(size 1 1)
					(thickness 0.15)
				)
			)
		)
		(property "Manufacturer" "Bourns"
			(at 56.23 365.59 0)
			(layer "F.Fab")
			(hide yes)
			(effects
				(font
					(size 1 1)
					(thickness 0.15)
				)
			)
		)
		(property "Tolerance" "1%"
			(at 56.23 365.59 0)
			(layer "F.Fab")
			(hide yes)
			(effects
				(font
					(size 1 1)
					(thickness 0.15)
				)
			)
		)
		(property "Val" "10k"
			(at 56.23 365.59 0)
			(layer "F.Fab")
			(hide yes)
			(effects
				(font
					(size 1 1)
					(thickness 0.15)
				)
			)
		)
		(sheetname "SPI Flash + SD Card")
		(sheetfile "spi-flash.kicad_sch")
		(attr smd)
		(fp_rect
			(start -0.925 -0.47)
			(end 0.925 0.47)
			(stroke
				(width 0.05)
				(type default)
			)
			(fill no)
			(layer "F.CrtYd")
		)
		(fp_rect
			(start -0.5 -0.25)
			(end 0.5 0.25)
			(stroke
				(width 0.15)
				(type solid)
			)
			(fill no)
			(layer "F.Fab")
		)
		(pad "1" smd roundrect
			(at -0.48 0 270)
			(size 0.59 0.64)
			(layers "F.Cu" "F.Mask" "F.Paste")
			(roundrect_rratio 0.25)
			(net 402 "/FPGA Bank 33 & 34/USR_FLASH_0.DQ3")
			(pintype "passive")
		)
		(pad "2" smd roundrect
			(at 0.48 0 270)
			(size 0.59 0.64)
			(layers "F.Cu" "F.Mask" "F.Paste")
			(roundrect_rratio 0.25)
			(net 26 "+1V8")
			(pintype "passive")
		)
	)
	(footprint "antmicro-footprints:R_0402_1005Metric"
		(layer "F.Cu")
		(at 235.9 115.55 180)
		(descr "Resistor SMD 0402")
		(tags "resistor SMD 0402")
		(property "Reference" "R101"
			(at -0.8 -0.35 180)
			(layer "F.SilkS")
			(effects
				(font
					(size 0.7 0.7)
					(thickness 0.15)
				)
				(justify left bottom)
			)
		)
		(property "Value" "R_0R_0402"
			(at 0 1.4 180)
			(layer "F.Fab")
			(effects
				(font
					(size 0.7 0.7)
					(thickness 0.15)
				)
				(justify left bottom)
			)
		)
		(property "Description" "SMD Chip Resistor, Jumper, 0 ohm, 100 mW, 0402 [1005 Metric], Thick Film, General Purpose"
			(at 0 0 180)
			(layer "F.Fab")
			(hide yes)
			(effects
				(font
					(size 1.27 1.27)
					(thickness 0.15)
				)
			)
		)
		(property "Author" "Antmicro"
			(at 471.8 231.1 0)
			(layer "F.Fab")
			(hide yes)
			(effects
				(font
					(size 1 1)
					(thickness 0.15)
				)
			)
		)
		(property "Current" "1A"
			(at 471.8 231.1 0)
			(layer "F.Fab")
			(hide yes)
			(effects
				(font
					(size 1 1)
					(thickness 0.15)
				)
			)
		)
		(property "License" "Apache-2.0"
			(at 471.8 231.1 0)
			(layer "F.Fab")
			(hide yes)
			(effects
				(font
					(size 1 1)
					(thickness 0.15)
				)
			)
		)
		(property "MPN" "ERJ2GE0R00X"
			(at 471.8 231.1 0)
			(layer "F.Fab")
			(hide yes)
			(effects
				(font
					(size 1 1)
					(thickness 0.15)
				)
			)
		)
		(property "Manufacturer" "Panasonic"
			(at 471.8 231.1 0)
			(layer "F.Fab")
			(hide yes)
			(effects
				(font
					(size 1 1)
					(thickness 0.15)
				)
			)
		)
		(property "Tolerance" ""
			(at 471.8 231.1 0)
			(layer "F.Fab")
			(hide yes)
			(effects
				(font
					(size 1 1)
					(thickness 0.15)
				)
			)
		)
		(property "Val" "0R"
			(at 471.8 231.1 0)
			(layer "F.Fab")
			(hide yes)
			(effects
				(font
					(size 1 1)
					(thickness 0.15)
				)
			)
		)
		(sheetname "SPI Flash + SD Card")
		(sheetfile "spi-flash.kicad_sch")
		(attr smd)
		(fp_rect
			(start -0.925 -0.47)
			(end 0.925 0.47)
			(stroke
				(width 0.05)
				(type default)
			)
			(fill no)
			(layer "F.CrtYd")
		)
		(fp_rect
			(start -0.5 -0.25)
			(end 0.5 0.25)
			(stroke
				(width 0.15)
				(type solid)
			)
			(fill no)
			(layer "F.Fab")
		)
		(pad "1" smd roundrect
			(at -0.48 0 180)
			(size 0.59 0.64)
			(layers "F.Cu" "F.Mask" "F.Paste")
			(roundrect_rratio 0.25)
			(net 429 "/FPGA Bank 16 & 17/USR_FLASH_1.DQ0")
			(pintype "passive")
		)
		(pad "2" smd roundrect
			(at 0.48 0 180)
			(size 0.59 0.64)
			(layers "F.Cu" "F.Mask" "F.Paste")
			(roundrect_rratio 0.25)
			(net 908 "/SPI Flash + SD Card/USR_FLASH_1_DQ0")
			(pintype "passive")
		)
	)
	(footprint "antmicro-footprints:PinHeader_2x3_P2.54mm_SMD"
		(layer "F.Cu")
		(at 212.7 96.9)
		(property "Reference" "J19"
			(at 3.6 3.45 180)
			(layer "F.SilkS")
			(effects
				(font
					(size 0.7 0.7)
					(thickness 0.15)
				)
				(justify left bottom)
			)
		)
		(property "Value" "PinHeader_2x3_P2.54mm_SMD"
			(at 5.31 10.794 90)
			(layer "F.Fab")
			(effects
				(font
					(size 0.7 0.7)
					(thickness 0.15)
				)
				(justify left bottom)
			)
		)
		(property "Author" "Antmicro"
			(at 0 0 0)
			(layer "F.Fab")
			(hide yes)
			(effects
				(font
					(size 1 1)
					(thickness 0.15)
				)
			)
		)
		(property "License" "Apache-2.0"
			(at 0 0 0)
			(layer "F.Fab")
			(hide yes)
			(effects
				(font
					(size 1 1)
					(thickness 0.15)
				)
			)
		)
		(property "MPN" "15910060"
			(at 0 0 0)
			(layer "F.Fab")
			(hide yes)
			(effects
				(font
					(size 1 1)
					(thickness 0.15)
				)
			)
		)
		(property "Manufacturer" "Molex"
			(at 0 0 0)
			(layer "F.Fab")
			(hide yes)
			(effects
				(font
					(size 1 1)
					(thickness 0.15)
				)
			)
		)
		(sheetname "FPGA supply")
		(sheetfile "fpga-supply.kicad_sch")
		(attr smd)
		(fp_line
			(start -3.809 -2.555)
			(end -3.269 -2.555)
			(stroke
				(width 0.15)
				(type solid)
			)
			(layer "F.SilkS")
		)
		(fp_line
			(start -3.809 2.521)
			(end -3.809 -2.555)
			(stroke
				(width 0.15)
				(type solid)
			)
			(layer "F.SilkS")
		)
		(fp_line
			(start -3.809 2.521)
			(end -3.269 2.521)
			(stroke
				(width 0.15)
				(type solid)
			)
			(layer "F.SilkS")
		)
		(fp_line
			(start 3.81 -2.555)
			(end 3.27 -2.555)
			(stroke
				(width 0.15)
				(type solid)
			)
			(layer "F.SilkS")
		)
		(fp_line
			(start 3.81 -2.555)
			(end 3.81 2.521)
			(stroke
				(width 0.15)
				(type solid)
			)
			(layer "F.SilkS")
		)
		(fp_line
			(start 3.81 2.521)
			(end 3.27 2.521)
			(stroke
				(width 0.15)
				(type solid)
			)
			(layer "F.SilkS")
		)
		(fp_circle
			(center -3.45 2.95)
			(end -3.397 2.95)
			(stroke
				(width 0.15)
				(type solid)
			)
			(fill yes)
			(layer "F.SilkS")
		)
		(fp_rect
			(start -4.31 -4.103)
			(end 4.309 4.101)
			(stroke
				(width 0.05)
				(type solid)
			)
			(fill no)
			(layer "F.CrtYd")
		)
		(fp_line
			(start -3.81 3.29)
			(end -3.61 3.49)
			(stroke
				(width 0.15)
				(type solid)
			)
			(layer "F.Fab")
		)
		(fp_rect
			(start -3.81 -3.493)
			(end 3.809 3.491)
			(stroke
				(width 0.15)
				(type solid)
			)
			(fill no)
			(layer "F.Fab")
		)
		(pad "1" smd rect
			(at -2.539 2.2)
			(size 1.27 3.68)
			(layers "F.Cu" "F.Mask" "F.Paste")
			(net 2 "VCC_USR_A")
			(pintype "passive")
		)
		(pad "2" smd rect
			(at -2.539 -2.2 180)
			(size 1.27 3.68)
			(layers "F.Cu" "F.Mask" "F.Paste")
			(net 24 "+3V3")
			(pintype "passive")
		)
		(pad "3" smd rect
			(at 0 2.2)
			(size 1.27 3.68)
			(layers "F.Cu" "F.Mask" "F.Paste")
			(net 26 "+1V8")
			(pintype "passive")
		)
		(pad "4" smd rect
			(at 0 -2.2 180)
			(size 1.27 3.68)
			(layers "F.Cu" "F.Mask" "F.Paste")
			(net 2 "VCC_USR_A")
			(pintype "passive")
		)
		(pad "5" smd rect
			(at 2.539 2.2)
			(size 1.27 3.68)
			(layers "F.Cu" "F.Mask" "F.Paste")
			(net 2 "VCC_USR_A")
			(pintype "passive")
		)
		(pad "6" smd rect
			(at 2.539 -2.2 180)
			(size 1.27 3.68)
			(layers "F.Cu" "F.Mask" "F.Paste")
			(net 727 "+1V2")
			(pintype "passive")
		)
	)
)
